(kicad_pcb
	(version 20241229)
	(generator "pcbnew")
	(generator_version "9.0")
	(general
		(thickness 1.6296)
		(legacy_teardrops no)
	)
	(paper "A3")
	(title_block
		(title "Thunderbolt to 10GbE adapter")
		(date "2026-04-21")
		(rev "1.1.0")
		(company "Antmicro Ltd")
		(comment 1 "www.antmicro.com")
		(comment 9 "footprints 141-145 of 703")
	)
	(layers
		(0 "F.Cu" signal)
		(4 "In1.Cu" signal)
		(6 "In2.Cu" signal)
		(8 "In3.Cu" signal)
		(10 "In4.Cu" signal)
		(12 "In5.Cu" signal)
		(14 "In6.Cu" signal)
		(2 "B.Cu" signal)
		(9 "F.Adhes" user "F.Adhesive")
		(11 "B.Adhes" user "B.Adhesive")
		(13 "F.Paste" user)
		(15 "B.Paste" user)
		(5 "F.SilkS" user "F.Silkscreen")
		(7 "B.SilkS" user "B.Silkscreen")
		(1 "F.Mask" user)
		(3 "B.Mask" user)
		(17 "Dwgs.User" user "User.Drawings")
		(19 "Cmts.User" user "User.Comments")
		(21 "Eco1.User" user "User.Eco1")
		(23 "Eco2.User" user "User.Eco2")
		(25 "Edge.Cuts" user)
		(27 "Margin" user)
		(31 "F.CrtYd" user "F.Courtyard")
		(29 "B.CrtYd" user "B.Courtyard")
		(35 "F.Fab" user)
		(33 "B.Fab" user)
	)
	(footprint "antmicro-footprints:C_0402_1005Metric"
		(layer "F.Cu")
		(at 125.75 134.75 90)
		(descr "Capacitor SMD 0402")
		(tags "capacitor SMD 0402")
		(property "Reference" "C36"
			(at -3.05 0.45 90)
			(layer "F.SilkS")
			(effects
				(font
					(size 0.7 0.7)
					(thickness 0.15)
				)
				(justify left bottom)
			)
		)
		(property "Value" "C_220n_0402"
			(at -1.022927 2.155213 90)
			(layer "F.Fab")
			(effects
				(font
					(size 0.7 0.7)
					(thickness 0.15)
				)
				(justify left bottom)
			)
		)
		(property "Datasheet" "https://www.yageo.com/en/Chart/Download/pdf/CC0402KRX5R6BB224"
			(at 0 0 90)
			(layer "F.Fab")
			(hide yes)
			(effects
				(font
					(size 1.27 1.27)
					(thickness 0.15)
				)
			)
		)
		(property "Description" "SMD Multilayer Ceramic Capacitor, 0.22 µF, 10 V, 0402 [1005 Metric], ± 10%, X5R, CC Series"
			(at 0 0 90)
			(layer "F.Fab")
			(hide yes)
			(effects
				(font
					(size 1.27 1.27)
					(thickness 0.15)
				)
			)
		)
		(property "MPN" "CC0402KRX5R6BB224"
			(at 0 0 90)
			(unlocked yes)
			(layer "F.Fab")
			(hide yes)
			(effects
				(font
					(size 1 1)
					(thickness 0.15)
				)
			)
		)
		(property "Manufacturer" "YAGEO"
			(at 0 0 90)
			(unlocked yes)
			(layer "F.Fab")
			(hide yes)
			(effects
				(font
					(size 1 1)
					(thickness 0.15)
				)
			)
		)
		(property "License" "Apache-2.0"
			(at 0 0 90)
			(unlocked yes)
			(layer "F.Fab")
			(hide yes)
			(effects
				(font
					(size 1 1)
					(thickness 0.15)
				)
			)
		)
		(property "Val" "220n"
			(at 0 0 90)
			(unlocked yes)
			(layer "F.Fab")
			(hide yes)
			(effects
				(font
					(size 1 1)
					(thickness 0.15)
				)
			)
		)
		(property "Voltage" ""
			(at 0 0 90)
			(unlocked yes)
			(layer "F.Fab")
			(hide yes)
			(effects
				(font
					(size 1 1)
					(thickness 0.15)
				)
			)
		)
		(property "Dielectric" ""
			(at 0 0 90)
			(unlocked yes)
			(layer "F.Fab")
			(hide yes)
			(effects
				(font
					(size 1 1)
					(thickness 0.15)
				)
			)
		)
		(property "Author" "Antmicro"
			(at 0 0 90)
			(unlocked yes)
			(layer "F.Fab")
			(hide yes)
			(effects
				(font
					(size 1 1)
					(thickness 0.15)
				)
			)
		)
		(sheetname "/TB Controller/")
		(sheetfile "tb.kicad_sch")
		(attr smd)
		(fp_rect
			(start -0.925 -0.47)
			(end 0.925 0.47)
			(stroke
				(width 0.05)
				(type default)
			)
			(fill no)
			(layer "F.CrtYd")
		)
		(fp_line
			(start 0.504 -0.25)
			(end 0.504 0.248)
			(stroke
				(width 0.15)
				(type solid)
			)
			(layer "F.Fab")
		)
		(fp_line
			(start -0.494 -0.25)
			(end 0.504 -0.25)
			(stroke
				(width 0.15)
				(type solid)
			)
			(layer "F.Fab")
		)
		(fp_line
			(start 0.504 0.248)
			(end -0.494 0.248)
			(stroke
				(width 0.15)
				(type solid)
			)
			(layer "F.Fab")
		)
		(fp_line
			(start -0.494 0.248)
			(end -0.494 -0.25)
			(stroke
				(width 0.15)
				(type solid)
			)
			(layer "F.Fab")
		)
		(fp_text user "${REFERENCE}"
			(at -0.939 4.599 90)
			(layer "F.Fab")
			(effects
				(font
					(size 0.7 0.7)
					(thickness 0.15)
				)
				(justify left bottom)
			)
		)
		(fp_text user "License: Apache-2.0"
			(at -0.939 5.799 90)
			(layer "F.Fab")
			(effects
				(font
					(size 0.7 0.7)
					(thickness 0.15)
				)
				(justify left bottom)
			)
		)
		(fp_text user "Author: Antmicro"
			(at -0.939 3.399 90)
			(layer "F.Fab")
			(effects
				(font
					(size 0.7 0.7)
					(thickness 0.15)
				)
				(justify left bottom)
			)
		)
		(pad "1" smd roundrect
			(at -0.48 0 90)
			(size 0.59 0.64)
			(layers "F.Cu" "F.Mask" "F.Paste")
			(roundrect_rratio 0.25)
			(net 311 "/PD and TB DC-DC/USB3.TX0_N")
			(pintype "passive")
		)
		(pad "2" smd roundrect
			(at 0.48 0 90)
			(size 0.59 0.64)
			(layers "F.Cu" "F.Mask" "F.Paste")
			(roundrect_rratio 0.25)
			(net 169 "/TB Controller/PA_TX0_N")
			(pintype "passive")
		)
	)
	(footprint "antmicro-footprints:C_0805_2012Metric"
		(layer "F.Cu")
		(at 119.65 107.75 180)
		(descr "Capacitor SMD 0805")
		(tags "capacitor SMD 0805")
		(property "Reference" "C7"
			(at -6.55 -6.35 180)
			(layer "F.SilkS")
			(effects
				(font
					(size 0.7 0.7)
					(thickness 0.15)
				)
			)
		)
		(property "Value" "C_22u_25V_0805"
			(at -2.055717 1.963152 180)
			(layer "F.Fab")
			(effects
				(font
					(size 0.7 0.7)
					(thickness 0.15)
				)
				(justify left bottom)
			)
		)
		(property "Datasheet" "https://product.samsungsem.com/mlcc/CL21A226MAYNNN.do"
			(at 0 0 180)
			(layer "F.Fab")
			(hide yes)
			(effects
				(font
					(size 1.27 1.27)
					(thickness 0.15)
				)
			)
		)
		(property "Description" "SMT Multilayer Ceramic Capacitor, 22uF, +/-20%, 25V, X5R, 0805 [2012 Metric]"
			(at 0 0 180)
			(layer "F.Fab")
			(hide yes)
			(effects
				(font
					(size 1.27 1.27)
					(thickness 0.15)
				)
			)
		)
		(property "MPN" "CL21A226MAYNNNE"
			(at 0 0 180)
			(unlocked yes)
			(layer "F.Fab")
			(hide yes)
			(effects
				(font
					(size 1 1)
					(thickness 0.15)
				)
			)
		)
		(property "Manufacturer" "Samsung Electro-Mechanics"
			(at 0 0 180)
			(unlocked yes)
			(layer "F.Fab")
			(hide yes)
			(effects
				(font
					(size 1 1)
					(thickness 0.15)
				)
			)
		)
		(property "License" "Apache-2.0"
			(at 0 0 180)
			(unlocked yes)
			(layer "F.Fab")
			(hide yes)
			(effects
				(font
					(size 1 1)
					(thickness 0.15)
				)
			)
		)
		(property "Author" "Antmicro"
			(at 0 0 180)
			(unlocked yes)
			(layer "F.Fab")
			(hide yes)
			(effects
				(font
					(size 1 1)
					(thickness 0.15)
				)
			)
		)
		(property "Val" "22u"
			(at 0 0 180)
			(unlocked yes)
			(layer "F.Fab")
			(hide yes)
			(effects
				(font
					(size 1 1)
					(thickness 0.15)
				)
			)
		)
		(property "Voltage" "25V"
			(at 0 0 180)
			(unlocked yes)
			(layer "F.Fab")
			(hide yes)
			(effects
				(font
					(size 1 1)
					(thickness 0.15)
				)
			)
		)
		(property "Dielectric" "X5R"
			(at 0 0 180)
			(unlocked yes)
			(layer "F.Fab")
			(hide yes)
			(effects
				(font
					(size 1 1)
					(thickness 0.15)
				)
			)
		)
		(property "Public" "False"
			(at 0 0 180)
			(unlocked yes)
			(layer "F.Fab")
			(hide yes)
			(effects
				(font
					(size 1 1)
					(thickness 0.15)
				)
			)
		)
		(sheetname "/PD and TB DC-DC/")
		(sheetfile "PD_and_TB_DC_DC.kicad_sch")
		(attr smd)
		(fp_line
			(start -0.3 0.7)
			(end 0.3 0.7)
			(stroke
				(width 0.15)
				(type solid)
			)
			(layer "F.SilkS")
		)
		(fp_line
			(start -0.3 -0.7)
			(end 0.3 -0.7)
			(stroke
				(width 0.15)
				(type solid)
			)
			(layer "F.SilkS")
		)
		(fp_rect
			(start 1.95 -0.9)
			(end -1.95 0.9)
			(stroke
				(width 0.05)
				(type default)
			)
			(fill no)
			(layer "F.CrtYd")
		)
		(fp_rect
			(start -0.95 -0.675)
			(end 0.95 0.675)
			(stroke
				(width 0.15)
				(type solid)
			)
			(fill no)
			(layer "F.Fab")
		)
		(fp_text user "License: Apache-2.0"
			(at -1.9 4.947 180)
			(layer "F.Fab")
			(effects
				(font
					(size 0.7 0.7)
					(thickness 0.15)
				)
				(justify left bottom)
			)
		)
		(fp_text user "Author: Antmicro"
			(at -1.9 5.947 180)
			(layer "F.Fab")
			(effects
				(font
					(size 0.7 0.7)
					(thickness 0.15)
				)
				(justify left bottom)
			)
		)
		(fp_text user "${REFERENCE}"
			(at -1.9 3.947 180)
			(layer "F.Fab")
			(effects
				(font
					(size 0.7 0.7)
					(thickness 0.15)
				)
				(justify left bottom)
			)
		)
		(pad "1" smd roundrect
			(at -1.1 0 180)
			(size 1.2 1.3)
			(layers "F.Cu" "F.Mask" "F.Paste")
			(roundrect_rratio 0.25)
			(net 23 "GND")
			(pintype "passive")
		)
		(pad "2" smd roundrect
			(at 1.1 0 180)
			(size 1.2 1.3)
			(layers "F.Cu" "F.Mask" "F.Paste")
			(roundrect_rratio 0.25)
			(net 161 "Net-(U2-VIN)")
			(pintype "passive")
		)
	)
	(footprint "antmicro-footprints:C_0603_1608Metric_EIA"
		(layer "F.Cu")
		(at 130.949999 96.25 -90)
		(descr "Capacitor SMD 0603, IPC-7351 Density Level A")
		(tags "Capacitor 0603")
		(property "Reference" "C109"
			(at -9.249999 -37.685 270)
			(layer "F.SilkS")
			(effects
				(font
					(size 0.7 0.7)
					(thickness 0.15)
				)
			)
		)
		(property "Value" "C_22u_16V_0603"
			(at -1.42757 1.770288 270)
			(layer "F.Fab")
			(effects
				(font
					(size 0.7 0.7)
					(thickness 0.15)
				)
				(justify left bottom)
			)
		)
		(property "Datasheet" "https://product.samsungsem.com/mlcc/CL10A226MO7JZN.do"
			(at 0 0 270)
			(layer "F.Fab")
			(hide yes)
			(effects
				(font
					(size 1.27 1.27)
					(thickness 0.15)
				)
			)
		)
		(property "Description" "SMD Multilayer Ceramic Capacitor"
			(at 0 0 270)
			(layer "F.Fab")
			(hide yes)
			(effects
				(font
					(size 1.27 1.27)
					(thickness 0.15)
				)
			)
		)
		(property "MPN" "CL10A226MO7JZNC"
			(at 0 0 270)
			(unlocked yes)
			(layer "F.Fab")
			(hide yes)
			(effects
				(font
					(size 1 1)
					(thickness 0.15)
				)
			)
		)
		(property "Manufacturer" "Samsung Electro-Mechanics"
			(at 0 0 270)
			(unlocked yes)
			(layer "F.Fab")
			(hide yes)
			(effects
				(font
					(size 1 1)
					(thickness 0.15)
				)
			)
		)
		(property "License" "Apache-2.0"
			(at 0 0 270)
			(unlocked yes)
			(layer "F.Fab")
			(hide yes)
			(effects
				(font
					(size 1 1)
					(thickness 0.15)
				)
			)
		)
		(property "Author" "Antmicro"
			(at 0 0 270)
			(unlocked yes)
			(layer "F.Fab")
			(hide yes)
			(effects
				(font
					(size 1 1)
					(thickness 0.15)
				)
			)
		)
		(property "Val" "22u"
			(at 0 0 270)
			(unlocked yes)
			(layer "F.Fab")
			(hide yes)
			(effects
				(font
					(size 1 1)
					(thickness 0.15)
				)
			)
		)
		(property "Voltage" "16V"
			(at 0 0 270)
			(unlocked yes)
			(layer "F.Fab")
			(hide yes)
			(effects
				(font
					(size 1 1)
					(thickness 0.15)
				)
			)
		)
		(property "Dielectric" ""
			(at 0 0 270)
			(unlocked yes)
			(layer "F.Fab")
			(hide yes)
			(effects
				(font
					(size 1 1)
					(thickness 0.15)
				)
			)
		)
		(sheetname "/X710 DCDC converters/")
		(sheetfile "DCDC_converters_X710.kicad_sch")
		(attr smd)
		(fp_line
			(start -0.15 0.55)
			(end 0.15 0.55)
			(stroke
				(width 0.15)
				(type solid)
			)
			(layer "F.SilkS")
		)
		(fp_line
			(start -0.15 -0.55)
			(end 0.15 -0.55)
			(stroke
				(width 0.15)
				(type solid)
			)
			(layer "F.SilkS")
		)
		(fp_rect
			(start -1.25 -0.65)
			(end 1.25 0.65)
			(stroke
				(width 0.05)
				(type solid)
			)
			(fill no)
			(layer "F.CrtYd")
		)
		(fp_rect
			(start -0.8 -0.45)
			(end 0.8 0.45)
			(stroke
				(width 0.15)
				(type solid)
			)
			(fill no)
			(layer "F.Fab")
		)
		(fp_text user "Author: Antmicro"
			(at -1.682 4.894 270)
			(layer "F.Fab")
			(effects
				(font
					(size 0.7 0.7)
					(thickness 0.15)
				)
				(justify left bottom)
			)
		)
		(fp_text user "License: Apache-2.0"
			(at -1.682 5.895 270)
			(layer "F.Fab")
			(effects
				(font
					(size 0.7 0.7)
					(thickness 0.15)
				)
				(justify left bottom)
			)
		)
		(fp_text user "${REFERENCE}"
			(at -1.682 3.895 270)
			(layer "F.Fab")
			(effects
				(font
					(size 0.7 0.7)
					(thickness 0.15)
				)
				(justify left bottom)
			)
		)
		(pad "1" smd roundrect
			(at -0.7 0 270)
			(size 0.8 1.1)
			(layers "F.Cu" "F.Mask" "F.Paste")
			(roundrect_rratio 0.2)
			(net 23 "GND")
			(pintype "passive")
		)
		(pad "2" smd roundrect
			(at 0.7 0 270)
			(size 0.8 1.1)
			(layers "F.Cu" "F.Mask" "F.Paste")
			(roundrect_rratio 0.2)
			(net 40 "+5V")
			(pintype "passive")
		)
	)
	(footprint "antmicro-footprints:C_0402_1005Metric"
		(layer "F.Cu")
		(at 135 84.2 90)
		(descr "Capacitor SMD 0402")
		(tags "capacitor SMD 0402")
		(property "Reference" "C274"
			(at -1.2 -4.2 90)
			(layer "F.SilkS")
			(effects
				(font
					(size 0.7 0.7)
					(thickness 0.15)
				)
				(justify left bottom)
			)
		)
		(property "Value" "C_100n_0402"
			(at -1.022927 2.155213 90)
			(layer "F.Fab")
			(effects
				(font
					(size 0.7 0.7)
					(thickness 0.15)
				)
				(justify left bottom)
			)
		)
		(property "Datasheet" "https://www.murata.com/products/productdetail?partno=GRM155R61H104KE14%23"
			(at 0 0 90)
			(layer "F.Fab")
			(hide yes)
			(effects
				(font
					(size 1.27 1.27)
					(thickness 0.15)
				)
			)
		)
		(property "Description" "SMD Multilayer Ceramic Capacitor, 0.1 µF, 50 V, 0402 [1005 Metric], ± 10%, X5R, GRM Series"
			(at 0 0 90)
			(layer "F.Fab")
			(hide yes)
			(effects
				(font
					(size 1.27 1.27)
					(thickness 0.15)
				)
			)
		)
		(property "MPN" "GRM155R61H104KE14D"
			(at 0 0 90)
			(unlocked yes)
			(layer "F.Fab")
			(hide yes)
			(effects
				(font
					(size 1 1)
					(thickness 0.15)
				)
			)
		)
		(property "Val" "100n"
			(at 0 0 90)
			(unlocked yes)
			(layer "F.Fab")
			(hide yes)
			(effects
				(font
					(size 1 1)
					(thickness 0.15)
				)
			)
		)
		(property "Voltage" "50V"
			(at 0 0 90)
			(unlocked yes)
			(layer "F.Fab")
			(hide yes)
			(effects
				(font
					(size 1 1)
					(thickness 0.15)
				)
			)
		)
		(property "Dielectric" "X5R"
			(at 0 0 90)
			(unlocked yes)
			(layer "F.Fab")
			(hide yes)
			(effects
				(font
					(size 1 1)
					(thickness 0.15)
				)
			)
		)
		(property "Manufacturer" "Murata"
			(at 0 0 90)
			(unlocked yes)
			(layer "F.Fab")
			(hide yes)
			(effects
				(font
					(size 1 1)
					(thickness 0.15)
				)
			)
		)
		(property "License" "Apache-2.0"
			(at 0 0 90)
			(unlocked yes)
			(layer "F.Fab")
			(hide yes)
			(effects
				(font
					(size 1 1)
					(thickness 0.15)
				)
			)
		)
		(property "Author" "Antmicro"
			(at 0 0 90)
			(unlocked yes)
			(layer "F.Fab")
			(hide yes)
			(effects
				(font
					(size 1 1)
					(thickness 0.15)
				)
			)
		)
		(sheetname "/X710-AT2 Misc/")
		(sheetfile "x710-at2-mics.kicad_sch")
		(attr smd)
		(fp_rect
			(start -0.925 -0.47)
			(end 0.925 0.47)
			(stroke
				(width 0.05)
				(type default)
			)
			(fill no)
			(layer "F.CrtYd")
		)
		(fp_line
			(start 0.504 -0.25)
			(end 0.504 0.248)
			(stroke
				(width 0.15)
				(type solid)
			)
			(layer "F.Fab")
		)
		(fp_line
			(start -0.494 -0.25)
			(end 0.504 -0.25)
			(stroke
				(width 0.15)
				(type solid)
			)
			(layer "F.Fab")
		)
		(fp_line
			(start 0.504 0.248)
			(end -0.494 0.248)
			(stroke
				(width 0.15)
				(type solid)
			)
			(layer "F.Fab")
		)
		(fp_line
			(start -0.494 0.248)
			(end -0.494 -0.25)
			(stroke
				(width 0.15)
				(type solid)
			)
			(layer "F.Fab")
		)
		(fp_text user "Author: Antmicro"
			(at -0.939 3.399 90)
			(layer "F.Fab")
			(effects
				(font
					(size 0.7 0.7)
					(thickness 0.15)
				)
				(justify left bottom)
			)
		)
		(fp_text user "${REFERENCE}"
			(at -0.939 4.599 90)
			(layer "F.Fab")
			(effects
				(font
					(size 0.7 0.7)
					(thickness 0.15)
				)
				(justify left bottom)
			)
		)
		(fp_text user "License: Apache-2.0"
			(at -0.939 5.799 90)
			(layer "F.Fab")
			(effects
				(font
					(size 0.7 0.7)
					(thickness 0.15)
				)
				(justify left bottom)
			)
		)
		(pad "1" smd roundrect
			(at -0.48 0 90)
			(size 0.59 0.64)
			(layers "F.Cu" "F.Mask" "F.Paste")
			(roundrect_rratio 0.25)
			(net 23 "GND")
			(pintype "passive")
		)
		(pad "2" smd roundrect
			(at 0.48 0 90)
			(size 0.59 0.64)
			(layers "F.Cu" "F.Mask" "F.Paste")
			(roundrect_rratio 0.25)
			(net 7 "+3V3")
			(pintype "passive")
		)
	)
	(footprint "antmicro-footprints:L_Bourns-SRP2512A"
		(layer "F.Cu")
		(at 151.955 96.374999 90)
		(property "Reference" "L9"
			(at -19.625001 23.294999 270)
			(layer "F.SilkS")
			(effects
				(font
					(size 0.7 0.7)
					(thickness 0.15)
				)
			)
		)
		(property "Value" "L_4u7_1.55A_Bourns-SRP2512A"
			(at 0 2.25 270)
			(layer "F.Fab")
			(effects
				(font
					(size 0.7 0.7)
					(thickness 0.15)
				)
				(justify left bottom)
			)
		)
		(property "Datasheet" "https://www.bourns.com/docs/Product-Datasheets/srp2512a.pdf"
			(at 0 0 90)
			(layer "F.Fab")
			(hide yes)
			(effects
				(font
					(size 1.27 1.27)
					(thickness 0.15)
				)
			)
		)
		(property "Description" "4.7 µH Shielded Drum Core, Wirewound Inductor 1.55 A 235mOhm Max 1008 (2520 Metric)"
			(at 0 0 90)
			(layer "F.Fab")
			(hide yes)
			(effects
				(font
					(size 1.27 1.27)
					(thickness 0.15)
				)
			)
		)
		(property "Val" "4u7/1.55A"
			(at 0 0 90)
			(unlocked yes)
			(layer "F.Fab")
			(hide yes)
			(effects
				(font
					(size 1 1)
					(thickness 0.15)
				)
			)
		)
		(property "Manufacturer" "Bourns"
			(at 0 0 90)
			(unlocked yes)
			(layer "F.Fab")
			(hide yes)
			(effects
				(font
					(size 1 1)
					(thickness 0.15)
				)
			)
		)
		(property "MPN" "SRP2512A-4R7M"
			(at 0 0 90)
			(unlocked yes)
			(layer "F.Fab")
			(hide yes)
			(effects
				(font
					(size 1 1)
					(thickness 0.15)
				)
			)
		)
		(property "ISat" "1.9 A"
			(at 0 0 90)
			(unlocked yes)
			(layer "F.Fab")
			(hide yes)
			(effects
				(font
					(size 1 1)
					(thickness 0.15)
				)
			)
		)
		(property "IMax" "1.55 A"
			(at 0 0 90)
			(unlocked yes)
			(layer "F.Fab")
			(hide yes)
			(effects
				(font
					(size 1 1)
					(thickness 0.15)
				)
			)
		)
		(property "Size" "2.5x2.0"
			(at 0 0 90)
			(unlocked yes)
			(layer "F.Fab")
			(hide yes)
			(effects
				(font
					(size 1 1)
					(thickness 0.15)
				)
			)
		)
		(property "Author" "Antmicro"
			(at 0 0 90)
			(unlocked yes)
			(layer "F.Fab")
			(hide yes)
			(effects
				(font
					(size 1 1)
					(thickness 0.15)
				)
			)
		)
		(property "License" "Apache-2.0"
			(at 0 0 90)
			(unlocked yes)
			(layer "F.Fab")
			(hide yes)
			(effects
				(font
					(size 1 1)
					(thickness 0.15)
				)
			)
		)
		(sheetname "/X710-AT2 power/")
		(sheetfile "x710-at2-power.kicad_sch")
		(attr smd)
		(fp_line
			(start -0.35 -1)
			(end 0.35 -1)
			(stroke
				(width 0.15)
				(type solid)
			)
			(layer "F.SilkS")
		)
		(fp_line
			(start -0.351 1)
			(end 0.349 1)
			(stroke
				(width 0.15)
				(type solid)
			)
			(layer "F.SilkS")
		)
		(fp_rect
			(start -1.65 -1.3)
			(end 1.65 1.3)
			(stroke
				(width 0.05)
				(type solid)
			)
			(fill no)
			(layer "F.CrtYd")
		)
		(fp_text user "License: Apache-2.0"
			(at -2.575 5.875 90)
			(layer "F.Fab")
			(effects
				(font
					(size 0.7 0.7)
					(thickness 0.15)
				)
				(justify left bottom)
			)
		)
		(fp_text user "${REFERENCE}"
			(at -2.575 3.475 90)
			(layer "F.Fab")
			(effects
				(font
					(size 0.7 0.7)
					(thickness 0.15)
				)
				(justify left bottom)
			)
		)
		(fp_text user "Author: Antmicro"
			(at -2.575 4.675 90)
			(layer "F.Fab")
			(effects
				(font
					(size 0.7 0.7)
					(thickness 0.15)
				)
				(justify left bottom)
			)
		)
		(pad "1" smd roundrect
			(at -1 0 180)
			(size 2 0.8)
			(layers "F.Cu" "F.Mask" "F.Paste")
			(roundrect_rratio 0.1)
			(net 136 "+1V0")
			(pintype "passive")
		)
		(pad "2" smd roundrect
			(at 1 0 180)
			(size 2 0.8)
			(layers "F.Cu" "F.Mask" "F.Paste")
			(roundrect_rratio 0.1)
			(net 12 "XFI_VDD")
			(pintype "passive")
		)
	)
)
